(kicad_pcb
	(version 20260206)
	(generator "pcbnew")
	(generator_version "10.0")
	(general
		(thickness 1.6)
		(legacy_teardrops no)
	)
	(paper "A4")
	(title_block
		(title "12092022_DA0F0TFB6D0_F0T_FAN_BOARD_MP5048_D_brd_v02_OCP.brd")
		(comment 1 "Grand Teton / footprints 831-832 of 924")
	)
	(layers
		(0 "F.Cu" signal "TOP")
		(4 "In1.Cu" signal "GND")
		(6 "In2.Cu" signal "IN1")
		(8 "In3.Cu" signal "IN2")
		(10 "In4.Cu" signal "GND1")
		(2 "B.Cu" signal "BOTTOM")
		(9 "F.Adhes" user "F.Adhesive")
		(11 "B.Adhes" user "B.Adhesive")
		(13 "F.Paste" user "Package Geometry/Pastemask Top")
		(15 "B.Paste" user "Package Geometry/Pastemask Bottom")
		(5 "F.SilkS" user "Ref Des/Silkscreen Top")
		(7 "B.SilkS" user "Ref Des/Silkscreen Bottom")
		(1 "F.Mask" user "Board Geometry/Soldermask Top")
		(3 "B.Mask" user "Board Geometry/Soldermask Bottom")
		(17 "Dwgs.User" user "User.Drawings")
		(19 "Cmts.User" user "User.Comments")
		(21 "Eco1.User" user "User.Eco1")
		(23 "Eco2.User" user "User.Eco2")
		(25 "Edge.Cuts" user "Board Geometry/Outline")
		(27 "Margin" user)
		(31 "F.CrtYd" user "Package Geometry/Place Bound Top")
		(29 "B.CrtYd" user "Package Geometry/Place Bound Bottom")
		(35 "F.Fab" user "Ref Des/Assembly Top")
		(33 "B.Fab" user "Ref Des/Assembly Bottom")
	)
	(footprint ""
		(layer "B.Cu")
		(at 37.31768 -244.39499)
		(property "Reference" "PU4"
			(at 5.22732 2.35966 0)
			(unlocked yes)
			(layer "B.SilkS")
			(effects
				(font
					(size 0.7874 0.5842)
					(thickness 0.1524)
				)
				(justify left mirror)
			)
		)
		(property "Value" ""
			(at 0 0 0)
			(layer "B.Fab")
			(effects
				(font
					(size 1.27 1.27)
				)
				(justify mirror)
			)
		)
		(duplicate_pad_numbers_are_jumpers no)
		(fp_line
			(start -2.549906 -2.549906)
			(end -2.4384 -2.549906)
			(stroke
				(width 0.1524)
				(type default)
			)
			(layer "B.SilkS")
		)
		(fp_line
			(start -2.549906 -2.2352)
			(end -2.549906 -2.549906)
			(stroke
				(width 0.1524)
				(type default)
			)
			(layer "B.SilkS")
		)
		(fp_line
			(start -2.549906 -1.4986)
			(end -2.549906 -1.7526)
			(stroke
				(width 0.1524)
				(type default)
			)
			(layer "B.SilkS")
		)
		(fp_line
			(start -2.549906 -0.6858)
			(end -2.549906 -0.9144)
			(stroke
				(width 0.1524)
				(type default)
			)
			(layer "B.SilkS")
		)
		(fp_line
			(start -2.549906 0.9144)
			(end -2.549906 -0.1016)
			(stroke
				(width 0.1524)
				(type default)
			)
			(layer "B.SilkS")
		)
		(fp_line
			(start -2.549906 1.7526)
			(end -2.549906 1.4986)
			(stroke
				(width 0.1524)
				(type default)
			)
			(layer "B.SilkS")
		)
		(fp_line
			(start -2.549906 2.549906)
			(end -2.549906 2.2352)
			(stroke
				(width 0.1524)
				(type default)
			)
			(layer "B.SilkS")
		)
		(fp_line
			(start -2.4384 2.549906)
			(end -2.549906 2.549906)
			(stroke
				(width 0.1524)
				(type default)
			)
			(layer "B.SilkS")
		)
		(fp_line
			(start -2.199894 2.9464)
			(end -2.199894 3.4544)
			(stroke
				(width 0.1524)
				(type default)
			)
			(layer "B.SilkS")
		)
		(fp_line
			(start -1.800098 -3.9624)
			(end -1.800098 -2.9464)
			(stroke
				(width 0.1524)
				(type default)
			)
			(layer "B.SilkS")
		)
		(fp_line
			(start -0.199898 2.9464)
			(end -0.199898 3.9624)
			(stroke
				(width 0.1524)
				(type default)
			)
			(layer "B.SilkS")
		)
		(fp_line
			(start 0.199898 -3.4544)
			(end 0.199898 -2.9464)
			(stroke
				(width 0.1524)
				(type default)
			)
			(layer "B.SilkS")
		)
		(fp_line
			(start 1.800098 2.9464)
			(end 1.800098 3.4544)
			(stroke
				(width 0.1524)
				(type default)
			)
			(layer "B.SilkS")
		)
		(fp_line
			(start 2.199894 -3.9624)
			(end 2.199894 -2.9464)
			(stroke
				(width 0.1524)
				(type default)
			)
			(layer "B.SilkS")
		)
		(fp_line
			(start 2.4384 -2.549906)
			(end 2.549906 -2.549906)
			(stroke
				(width 0.1524)
				(type default)
			)
			(layer "B.SilkS")
		)
		(fp_line
			(start 2.549906 -2.549906)
			(end 2.549906 -2.2352)
			(stroke
				(width 0.1524)
				(type default)
			)
			(layer "B.SilkS")
		)
		(fp_line
			(start 2.549906 -1.7526)
			(end 2.549906 -1.4986)
			(stroke
				(width 0.1524)
				(type default)
			)
			(layer "B.SilkS")
		)
		(fp_line
			(start 2.549906 -0.9144)
			(end 2.549906 0.1016)
			(stroke
				(width 0.1524)
				(type default)
			)
			(layer "B.SilkS")
		)
		(fp_line
			(start 2.549906 0.6858)
			(end 2.549906 0.9144)
			(stroke
				(width 0.1524)
				(type default)
			)
			(layer "B.SilkS")
		)
		(fp_line
			(start 2.549906 1.4986)
			(end 2.549906 1.7526)
			(stroke
				(width 0.1524)
				(type default)
			)
			(layer "B.SilkS")
		)
		(fp_line
			(start 2.549906 2.2352)
			(end 2.549906 2.549906)
			(stroke
				(width 0.1524)
				(type default)
			)
			(layer "B.SilkS")
		)
		(fp_line
			(start 2.549906 2.549906)
			(end 2.4384 2.549906)
			(stroke
				(width 0.1524)
				(type default)
			)
			(layer "B.SilkS")
		)
		(fp_poly
			(pts
				(xy 3.7084 -1.584706) (xy 2.939034 -1.199896) (xy 3.7084 -0.81534)
			)
			(stroke
				(width 0)
				(type default)
			)
			(fill yes)
			(layer "B.SilkS")
		)
		(fp_line
			(start -2.549906 -2.549906)
			(end 2.549906 -2.549906)
			(stroke
				(width 0.1)
				(type default)
			)
			(layer "B.Fab")
		)
		(fp_line
			(start -2.549906 2.549906)
			(end -2.549906 -2.549906)
			(stroke
				(width 0.1)
				(type default)
			)
			(layer "B.Fab")
		)
		(fp_line
			(start -2.199894 2.9464)
			(end -2.199894 3.4544)
			(stroke
				(width 0.1)
				(type default)
			)
			(layer "B.Fab")
		)
		(fp_line
			(start -1.800098 -3.9624)
			(end -1.800098 -2.9464)
			(stroke
				(width 0.1)
				(type default)
			)
			(layer "B.Fab")
		)
		(fp_line
			(start -0.199898 2.9464)
			(end -0.199898 3.9624)
			(stroke
				(width 0.1)
				(type default)
			)
			(layer "B.Fab")
		)
		(fp_line
			(start 0.199898 -3.4544)
			(end 0.199898 -2.9464)
			(stroke
				(width 0.1)
				(type default)
			)
			(layer "B.Fab")
		)
		(fp_line
			(start 1.800098 2.9464)
			(end 1.800098 3.4544)
			(stroke
				(width 0.1)
				(type default)
			)
			(layer "B.Fab")
		)
		(fp_line
			(start 2.199894 -3.9624)
			(end 2.199894 -2.9464)
			(stroke
				(width 0.1)
				(type default)
			)
			(layer "B.Fab")
		)
		(fp_line
			(start 2.549906 -2.549906)
			(end 2.549906 2.549906)
			(stroke
				(width 0.1)
				(type default)
			)
			(layer "B.Fab")
		)
		(fp_line
			(start 2.549906 2.549906)
			(end -2.549906 2.549906)
			(stroke
				(width 0.1)
				(type default)
			)
			(layer "B.Fab")
		)
		(fp_poly
			(pts
				(xy 3.7084 -1.584706) (xy 2.939034 -1.199896) (xy 3.7084 -0.81534)
			)
			(stroke
				(width 0)
				(type default)
			)
			(fill yes)
			(layer "B.Fab")
		)
		(fp_text user "16"
			(at -3.329432 1.2192 270)
			(unlocked yes)
			(layer "B.SilkS")
			(effects
				(font
					(size 0.635 0.4064)
					(thickness 0.1524)
				)
				(justify mirror)
			)
		)
		(fp_text user "18"
			(at -3.304032 -1.2192 270)
			(unlocked yes)
			(layer "B.SilkS")
			(effects
				(font
					(size 0.635 0.4064)
					(thickness 0.1524)
				)
				(justify mirror)
			)
		)
		(fp_text user "15"
			(at -2.8956 3.126232 0)
			(unlocked yes)
			(layer "B.SilkS")
			(effects
				(font
					(size 0.635 0.4064)
					(thickness 0.1524)
				)
				(justify mirror)
			)
		)
		(fp_text user "19"
			(at -2.8448 -3.096768 0)
			(unlocked yes)
			(layer "B.SilkS")
			(effects
				(font
					(size 0.635 0.4064)
					(thickness 0.1524)
				)
				(justify mirror)
			)
		)
		(fp_text user "4"
			(at 2.6416 3.151632 0)
			(unlocked yes)
			(layer "B.SilkS")
			(effects
				(font
					(size 0.635 0.4064)
					(thickness 0.1524)
				)
				(justify mirror)
			)
		)
		(fp_text user "30"
			(at 2.9464 -3.045968 0)
			(unlocked yes)
			(layer "B.SilkS")
			(effects
				(font
					(size 0.635 0.4064)
					(thickness 0.1524)
				)
				(justify mirror)
			)
		)
		(fp_text user "3"
			(at 3.299968 1.1938 270)
			(unlocked yes)
			(layer "B.SilkS")
			(effects
				(font
					(size 0.635 0.4064)
					(thickness 0.1524)
				)
				(justify mirror)
			)
		)
		(fp_text user "16"
			(at -3.329432 1.2192 270)
			(unlocked yes)
			(layer "B.Fab")
			(effects
				(font
					(size 0.635 0.4064)
					(thickness 0.1524)
				)
				(justify mirror)
			)
		)
		(fp_text user "18"
			(at -3.304032 -1.2192 270)
			(unlocked yes)
			(layer "B.Fab")
			(effects
				(font
					(size 0.635 0.4064)
					(thickness 0.1524)
				)
				(justify mirror)
			)
		)
		(fp_text user "15"
			(at -2.8956 3.126232 0)
			(unlocked yes)
			(layer "B.Fab")
			(effects
				(font
					(size 0.635 0.4064)
					(thickness 0.1524)
				)
				(justify mirror)
			)
		)
		(fp_text user "19"
			(at -2.8448 -3.096768 0)
			(unlocked yes)
			(layer "B.Fab")
			(effects
				(font
					(size 0.635 0.4064)
					(thickness 0.1524)
				)
				(justify mirror)
			)
		)
		(fp_text user "4"
			(at 2.6416 3.151632 0)
			(unlocked yes)
			(layer "B.Fab")
			(effects
				(font
					(size 0.635 0.4064)
					(thickness 0.1524)
				)
				(justify mirror)
			)
		)
		(fp_text user "30"
			(at 2.9464 -3.045968 0)
			(unlocked yes)
			(layer "B.Fab")
			(effects
				(font
					(size 0.635 0.4064)
					(thickness 0.1524)
				)
				(justify mirror)
			)
		)
		(fp_text user "3"
			(at 3.299968 1.1938 270)
			(unlocked yes)
			(layer "B.Fab")
			(effects
				(font
					(size 0.635 0.4064)
					(thickness 0.1524)
				)
				(justify mirror)
			)
		)
		(pad "1" smd circle
			(at 1.599946 -1.199896 270)
			(size 0 0)
			(layers "B.Cu" "B.Mask" "B.Paste")
			(net "P52V_HSC")
		)
		(pad "2" smd rect
			(at 1.549908 0.40005 90)
			(size 0.3048 2.5146)
			(layers "B.Cu" "B.Mask" "B.Paste")
			(net "P52V_HSC")
		)
		(pad "3" smd rect
			(at 1.549908 1.199896 90)
			(size 0.3048 2.5146)
			(layers "B.Cu" "B.Mask" "B.Paste")
			(net "P52V_FAN_1")
		)
		(pad "4" smd circle
			(at 2.199894 2.350008)
			(size 0 0)
			(layers "B.Cu" "B.Mask" "B.Paste")
			(net "P52V_FAN_1")
		)
		(pad "5" smd rect
			(at 1.800098 2.350008 180)
			(size 0.1778 0.9144)
			(layers "B.Cu" "B.Mask" "B.Paste")
			(net "P52V_FAN_1")
		)
		(pad "6" smd rect
			(at 1.400048 2.350008 180)
			(size 0.1778 0.9144)
			(layers "B.Cu" "B.Mask" "B.Paste")
			(net "P52V_FAN_1")
		)
		(pad "7" smd rect
			(at 0.999998 2.350008 180)
			(size 0.1778 0.9144)
			(layers "B.Cu" "B.Mask" "B.Paste")
			(net "P52V_FAN_1")
		)
		(pad "8" smd rect
			(at 0.599948 2.350008 180)
			(size 0.1778 0.9144)
			(layers "B.Cu" "B.Mask" "B.Paste")
			(net "P52V_FAN_1")
		)
		(pad "9" smd rect
			(at 0.199898 2.350008 180)
			(size 0.1778 0.9144)
			(layers "B.Cu" "B.Mask" "B.Paste")
			(net "P52V_FAN_1")
		)
		(pad "10" smd rect
			(at -0.199898 2.350008 180)
			(size 0.1778 0.9144)
			(layers "B.Cu" "B.Mask" "B.Paste")
			(net "P52V_FAN_1")
		)
		(pad "11" smd rect
			(at -0.599948 2.350008 180)
			(size 0.1778 0.9144)
			(layers "B.Cu" "B.Mask" "B.Paste")
			(net "P52V_FAN_1")
		)
		(pad "12" smd rect
			(at -0.999998 2.350008 180)
			(size 0.1778 0.9144)
			(layers "B.Cu" "B.Mask" "B.Paste")
			(net "P52V_FAN_1")
		)
		(pad "13" smd rect
			(at -1.400048 2.350008 180)
			(size 0.1778 0.9144)
			(layers "B.Cu" "B.Mask" "B.Paste")
			(net "P52V_FAN_1")
		)
		(pad "14" smd rect
			(at -1.800098 2.350008 180)
			(size 0.1778 0.9144)
			(layers "B.Cu" "B.Mask" "B.Paste")
			(net "P52V_FAN_1")
		)
		(pad "15" smd circle
			(at -2.199894 2.350008)
			(size 0 0)
			(layers "B.Cu" "B.Mask" "B.Paste")
			(net "P52V_FAN_1")
		)
		(pad "16" smd rect
			(at -1.549908 1.199896 90)
			(size 0.3048 2.5146)
			(layers "B.Cu" "B.Mask" "B.Paste")
			(net "P52V_FAN_1")
		)
		(pad "17" smd rect
			(at -1.549908 -0.40005 90)
			(size 0.3048 2.5146)
			(layers "B.Cu" "B.Mask" "B.Paste")
			(net "P52V_FAN_1")
		)
		(pad "18" smd rect
			(at -1.549908 -1.199896 90)
			(size 0.3048 2.5146)
			(layers "B.Cu" "B.Mask" "B.Paste")
			(net "P52V_HSC")
		)
		(pad "19" smd circle
			(at -2.199894 -2.350008 180)
			(size 0 0)
			(layers "B.Cu" "B.Mask" "B.Paste")
			(net "FAN_1_CS")
		)
		(pad "20" smd rect
			(at -1.800098 -2.350008 180)
			(size 0.1778 0.9144)
			(layers "B.Cu" "B.Mask" "B.Paste")
			(net "FAN_1_IMON")
		)
		(pad "21" smd rect
			(at -1.400048 -2.350008 180)
			(size 0.1778 0.9144)
			(layers "B.Cu" "B.Mask" "B.Paste")
			(net "FAN_1_SS")
		)
		(pad "22" smd rect
			(at -0.999998 -2.350008 180)
			(size 0.1778 0.9144)
			(layers "B.Cu" "B.Mask" "B.Paste")
			(net "FAN_1_FAULT")
		)
		(pad "23" smd rect
			(at -0.599948 -2.350008 180)
			(size 0.1778 0.9144)
			(layers "B.Cu" "B.Mask" "B.Paste")
			(net "FAN_1_TIMER")
		)
		(pad "24" smd rect
			(at -0.199898 -2.350008 180)
			(size 0.1778 0.9144)
			(layers "B.Cu" "B.Mask" "B.Paste")
			(net "FAN_1_CLREF")
		)
		(pad "25" smd rect
			(at 0.199898 -2.350008 180)
			(size 0.1778 0.9144)
			(layers "B.Cu" "B.Mask" "B.Paste")
			(net "GND")
		)
		(pad "26" smd rect
			(at 0.599948 -2.350008 180)
			(size 0.1778 0.9144)
			(layers "B.Cu" "B.Mask" "B.Paste")
			(net "FAN_1_ON")
		)
		(pad "27" smd rect
			(at 0.999998 -2.350008 180)
			(size 0.1778 0.9144)
			(layers "B.Cu" "B.Mask" "B.Paste")
			(net "FAN_1_P3V_R")
		)
		(pad "28" smd rect
			(at 1.400048 -2.350008 180)
			(size 0.1778 0.9144)
			(layers "B.Cu" "B.Mask" "B.Paste")
			(net "FAN_1_P5V")
		)
		(pad "29" smd rect
			(at 1.800098 -2.350008 180)
			(size 0.1778 0.9144)
			(layers "B.Cu" "B.Mask" "B.Paste")
			(net "FAN_1_TEMP")
		)
		(pad "30" smd circle
			(at 2.199894 -2.350008 180)
			(size 0 0)
			(layers "B.Cu" "B.Mask" "B.Paste")
			(net "FAN_1_MODE")
		)
	)
	(footprint ""
		(layer "B.Cu")
		(at 32.380428 -64.827912 -90)
		(property "Reference" "PR26"
			(at 0 0 90)
			(layer "B.SilkS")
			(hide yes)
			(effects
				(font
					(size 1.27 1.27)
				)
				(justify mirror)
			)
		)
		(property "Value" ""
			(at 0 0 90)
			(layer "B.Fab")
			(effects
				(font
					(size 1.27 1.27)
				)
				(justify mirror)
			)
		)
		(duplicate_pad_numbers_are_jumpers no)
		(fp_line
			(start -0.7874 0.4064)
			(end 0.7874 0.4064)
			(stroke
				(width 0.1524)
				(type default)
			)
			(layer "B.SilkS")
		)
		(fp_line
			(start 0.7874 0.4064)
			(end 0.7874 -0.4064)
			(stroke
				(width 0.1524)
				(type default)
			)
			(layer "B.SilkS")
		)
		(fp_line
			(start -0.7874 -0.4064)
			(end -0.7874 0.4064)
			(stroke
				(width 0.1524)
				(type default)
			)
			(layer "B.SilkS")
		)
		(fp_line
			(start 0.7874 -0.4064)
			(end -0.7874 -0.4064)
			(stroke
				(width 0.1524)
				(type default)
			)
			(layer "B.SilkS")
		)
		(fp_line
			(start -0.67945 0.3048)
			(end -0.120396 0.3048)
			(stroke
				(width 0.1)
				(type default)
			)
			(layer "B.Fab")
		)
		(fp_line
			(start -0.120396 0.3048)
			(end -0.120396 0.2794)
			(stroke
				(width 0.1)
				(type default)
			)
			(layer "B.Fab")
		)
		(fp_line
			(start 0.12065 0.3048)
			(end 0.67945 0.3048)
			(stroke
				(width 0.1)
				(type default)
			)
			(layer "B.Fab")
		)
		(fp_line
			(start 0.67945 0.3048)
			(end 0.67945 -0.305054)
			(stroke
				(width 0.1)
				(type default)
			)
			(layer "B.Fab")
		)
		(fp_line
			(start -0.120396 0.2794)
			(end 0.12065 0.2794)
			(stroke
				(width 0.1)
				(type default)
			)
			(layer "B.Fab")
		)
		(fp_line
			(start 0.12065 0.2794)
			(end 0.12065 0.3048)
			(stroke
				(width 0.1)
				(type default)
			)
			(layer "B.Fab")
		)
		(fp_line
			(start -0.12065 -0.2794)
			(end -0.12065 -0.3048)
			(stroke
				(width 0.1)
				(type default)
			)
			(layer "B.Fab")
		)
		(fp_line
			(start 0.12065 -0.2794)
			(end -0.12065 -0.2794)
			(stroke
				(width 0.1)
				(type default)
			)
			(layer "B.Fab")
		)
		(fp_line
			(start -0.67945 -0.3048)
			(end -0.67945 0.3048)
			(stroke
				(width 0.1)
				(type default)
			)
			(layer "B.Fab")
		)
		(fp_line
			(start -0.12065 -0.3048)
			(end -0.67945 -0.3048)
			(stroke
				(width 0.1)
				(type default)
			)
			(layer "B.Fab")
		)
		(fp_line
			(start 0.12065 -0.305054)
			(end 0.12065 -0.2794)
			(stroke
				(width 0.1)
				(type default)
			)
			(layer "B.Fab")
		)
		(fp_line
			(start 0.67945 -0.305054)
			(end 0.12065 -0.305054)
			(stroke
				(width 0.1)
				(type default)
			)
			(layer "B.Fab")
		)
		(pad "1" smd circle
			(at 0.40005 0 90)
			(size 0 0)
			(layers "B.Cu" "B.Mask" "B.Paste")
			(net "FAN_3_CS")
		)
		(pad "2" smd circle
			(at -0.40005 0 90)
			(size 0 0)
			(layers "B.Cu" "B.Mask" "B.Paste")
			(net "GND")
		)
	)
)
